G04 ================== begin FILE IDENTIFICATION RECORD ==================*
G04 Layout Name:  17301-sa.brd*
G04 Film Name:    BSMD*
G04 File Format:  Gerber RS274X*
G04 File Origin:  Cadence Allegro 16.6-2015-S079*
G04 Origin Date:  Thu Jun 22 17:49:49 2017*
G04 *
G04 Layer:  PIN/PASTEMASK_BOTTOM*
G04 Layer:  PACKAGE GEOMETRY/PASTEMASK_BOTTOM*
G04 Layer:  DRAWING FORMAT/LAYER_PAST_B*
G04 Layer:  VIA CLASS/PASTEMASK_BOTTOM*
G04 Layer:  DRAWING FORMAT/LAYER_PCB_STORY*
G04 Layer:  BOARD GEOMETRY/PANEL_OUTLINE*
G04 *
G04 Offset:    (0.00 0.00)*
G04 Mirror:    No*
G04 Mode:      Positive*
G04 Rotation:  0*
G04 FullContactRelief:  No*
G04 UndefLineWidth:     6.00*
G04 ================== end FILE IDENTIFICATION RECORD ====================*
%FSLAX35Y35*MOIN*%
%IR0*IPPOS*OFA0.00000B0.00000*MIA0B0*SFA1.00000B1.00000*%
%AMMACRO18*
4,1,40,.011,.007,
.011,-.007,
.010939,-.007695,
.010759,-.008368,
.010464,-.009,
.010064,-.009571,
.009571,-.010064,
.009,-.010464,
.008368,-.010759,
.007695,-.010939,
.007,-.011,
-.007,-.011,
-.007695,-.010939,
-.008368,-.010759,
-.009,-.010464,
-.009571,-.010064,
-.010064,-.009571,
-.010464,-.009,
-.010759,-.008368,
-.010939,-.007695,
-.011,-.007,
-.011,.007,
-.010939,.007695,
-.010759,.008368,
-.010464,.009,
-.010064,.009571,
-.009571,.010064,
-.009,.010464,
-.008368,.010759,
-.007695,.010939,
-.007,.011,
.007,.011,
.007695,.010939,
.008368,.010759,
.009,.010464,
.009571,.010064,
.010064,.009571,
.010464,.009,
.010759,.008368,
.010939,.007695,
.011,.007,
0.0*
%
%ADD18MACRO18*%
%AMMACRO31*
4,1,40,.013,-.017,
-.013,-.017,
-.013695,-.016939,
-.014368,-.016759,
-.015,-.016464,
-.015571,-.016064,
-.016064,-.015571,
-.016464,-.015,
-.016759,-.014368,
-.016939,-.013695,
-.017,-.013,
-.017,.013,
-.016939,.013695,
-.016759,.014368,
-.016464,.015,
-.016064,.015571,
-.015571,.016064,
-.015,.016464,
-.014368,.016759,
-.013695,.016939,
-.013,.017,
.013,.017,
.013695,.016939,
.014368,.016759,
.015,.016464,
.015571,.016064,
.016064,.015571,
.016464,.015,
.016759,.014368,
.016939,.013695,
.017,.013,
.017,-.013,
.016939,-.013695,
.016759,-.014368,
.016464,-.015,
.016064,-.015571,
.015571,-.016064,
.015,-.016464,
.014368,-.016759,
.013695,-.016939,
.013,-.017,
0.0*
%
%ADD31MACRO31*%
%ADD11C,.04*%
%ADD14C,.028*%
%ADD10C,.086*%
%AMMACRO23*
4,1,44,.023,.00387,
.022901,.005261,
.022562,.006614,
.021993,.007887,
.021211,.009042,
.020241,.010044,
.019112,.010863,
.017857,.011472,
.016516,.011855,
.015129,.011999,
.015,.012,
-.015,.012,
-.016389,.011878,
-.017737,.011517,
-.019001,.010928,
-.020143,.010128,
-.021129,.009142,
-.021929,.007999,
-.022519,.006735,
-.022879,.005388,
-.023001,.003999,
-.023,.00387,
-.023,-.00387,
-.022901,-.005261,
-.022562,-.006614,
-.021993,-.007887,
-.021211,-.009042,
-.020241,-.010044,
-.019112,-.010863,
-.017857,-.011472,
-.016516,-.011855,
-.015129,-.011999,
-.015,-.012,
.015,-.012,
.016389,-.011878,
.017737,-.011517,
.019001,-.010928,
.020143,-.010128,
.021129,-.009142,
.021929,-.007999,
.022519,-.006735,
.022879,-.005388,
.023001,-.003999,
.023,-.00387,
.023,.00387,
0.0*
%
%ADD23MACRO23*%
%AMMACRO34*
4,1,40,-.012,-.008,
-.012,.008,
-.011939,.008695,
-.011759,.009368,
-.011464,.01,
-.011064,.010571,
-.010571,.011064,
-.01,.011464,
-.009368,.011759,
-.008695,.011939,
-.008,.012,
.008,.012,
.008695,.011939,
.009368,.011759,
.01,.011464,
.010571,.011064,
.011064,.010571,
.011464,.01,
.011759,.009368,
.011939,.008695,
.012,.008,
.012,-.008,
.011939,-.008695,
.011759,-.009368,
.011464,-.01,
.011064,-.010571,
.010571,-.011064,
.01,-.011464,
.009368,-.011759,
.008695,-.011939,
.008,-.012,
-.008,-.012,
-.008695,-.011939,
-.009368,-.011759,
-.01,-.011464,
-.010571,-.011064,
-.011064,-.010571,
-.011464,-.01,
-.011759,-.009368,
-.011939,-.008695,
-.012,-.008,
0.0*
%
%ADD34MACRO34*%
%AMMACRO21*
4,1,40,-.013,.017,
.013,.017,
.013695,.016939,
.014368,.016759,
.015,.016464,
.015571,.016064,
.016064,.015571,
.016464,.015,
.016759,.014368,
.016939,.013695,
.017,.013,
.017,-.013,
.016939,-.013695,
.016759,-.014368,
.016464,-.015,
.016064,-.015571,
.015571,-.016064,
.015,-.016464,
.014368,-.016759,
.013695,-.016939,
.013,-.017,
-.013,-.017,
-.013695,-.016939,
-.014368,-.016759,
-.015,-.016464,
-.015571,-.016064,
-.016064,-.015571,
-.016464,-.015,
-.016759,-.014368,
-.016939,-.013695,
-.017,-.013,
-.017,.013,
-.016939,.013695,
-.016759,.014368,
-.016464,.015,
-.016064,.015571,
-.015571,.016064,
-.015,.016464,
-.014368,.016759,
-.013695,.016939,
-.013,.017,
0.0*
%
%ADD21MACRO21*%
%AMMACRO33*
4,1,40,-.012,-.008,
-.012,.008,
-.011939,.008695,
-.011759,.009368,
-.011464,.01,
-.011064,.010571,
-.010571,.011064,
-.01,.011464,
-.009368,.011759,
-.008695,.011939,
-.008,.012,
.008,.012,
.008695,.011939,
.009368,.011759,
.01,.011464,
.010571,.011064,
.011064,.010571,
.011464,.01,
.011759,.009368,
.011939,.008695,
.012,.008,
.012,-.008,
.011939,-.008695,
.011759,-.009368,
.011464,-.01,
.011064,-.010571,
.010571,-.011064,
.01,-.011464,
.009368,-.011759,
.008695,-.011939,
.008,-.012,
-.008,-.012,
-.008695,-.011939,
-.009368,-.011759,
-.01,-.011464,
-.010571,-.011064,
-.011064,-.010571,
-.011464,-.01,
-.011759,-.009368,
-.011939,-.008695,
-.012,-.008,
0.0*
%
%ADD33MACRO33*%
%AMMACRO22*
4,1,40,-.013,.017,
.013,.017,
.013695,.016939,
.014368,.016759,
.015,.016464,
.015571,.016064,
.016064,.015571,
.016464,.015,
.016759,.014368,
.016939,.013695,
.017,.013,
.017,-.013,
.016939,-.013695,
.016759,-.014368,
.016464,-.015,
.016064,-.015571,
.015571,-.016064,
.015,-.016464,
.014368,-.016759,
.013695,-.016939,
.013,-.017,
-.013,-.017,
-.013695,-.016939,
-.014368,-.016759,
-.015,-.016464,
-.015571,-.016064,
-.016064,-.015571,
-.016464,-.015,
-.016759,-.014368,
-.016939,-.013695,
-.017,-.013,
-.017,.013,
-.016939,.013695,
-.016759,.014368,
-.016464,.015,
-.016064,.015571,
-.015571,.016064,
-.015,.016464,
-.014368,.016759,
-.013695,.016939,
-.013,.017,
0.0*
%
%ADD22MACRO22*%
%ADD32R,.04X.022*%
%ADD29R,.016X.04*%
%ADD12R,.071X.032*%
%ADD13R,.063X.024*%
%ADD25R,.05X.065*%
%ADD24R,.047X.014*%
%ADD16R,.065X.025*%
%ADD35R,.045X.055*%
%ADD28R,.016X.048*%
%AMMACRO15*
4,1,40,-.007,.0225,
-.008389,.022378,
-.009736,.022018,
-.011,.021428,
-.012142,.020628,
-.013128,.019642,
-.013928,.0185,
-.014518,.017236,
-.014878,.015889,
-.015,.0145,
-.015,-.0145,
-.014878,-.015889,
-.014518,-.017236,
-.013928,-.0185,
-.013128,-.019642,
-.012142,-.020628,
-.011,-.021428,
-.009736,-.022018,
-.008389,-.022378,
-.007,-.0225,
.007,-.0225,
.008389,-.022378,
.009736,-.022018,
.011,-.021428,
.012142,-.020628,
.013128,-.019642,
.013928,-.0185,
.014518,-.017236,
.014878,-.015889,
.015,-.0145,
.015,.0145,
.014878,.015889,
.014518,.017236,
.013928,.0185,
.013128,.019642,
.012142,.020628,
.011,.021428,
.009736,.022018,
.008389,.022378,
.007,.0225,
-.007,.0225,
0.0*
%
%ADD15MACRO15*%
%AMMACRO27*
4,1,40,.012,.008,
.012,-.008,
.011939,-.008695,
.011759,-.009368,
.011464,-.01,
.011064,-.010571,
.010571,-.011064,
.01,-.011464,
.009368,-.011759,
.008695,-.011939,
.008,-.012,
-.008,-.012,
-.008695,-.011939,
-.009368,-.011759,
-.01,-.011464,
-.010571,-.011064,
-.011064,-.010571,
-.011464,-.01,
-.011759,-.009368,
-.011939,-.008695,
-.012,-.008,
-.012,.008,
-.011939,.008695,
-.011759,.009368,
-.011464,.01,
-.011064,.010571,
-.010571,.011064,
-.01,.011464,
-.009368,.011759,
-.008695,.011939,
-.008,.012,
.008,.012,
.008695,.011939,
.009368,.011759,
.01,.011464,
.010571,.011064,
.011064,.010571,
.011464,.01,
.011759,.009368,
.011939,.008695,
.012,.008,
0.0*
%
%ADD27MACRO27*%
%AMMACRO20*
4,1,40,.008,-.012,
-.008,-.012,
-.008695,-.011939,
-.009368,-.011759,
-.01,-.011464,
-.010571,-.011064,
-.011064,-.010571,
-.011464,-.01,
-.011759,-.009368,
-.011939,-.008695,
-.012,-.008,
-.012,.008,
-.011939,.008695,
-.011759,.009368,
-.011464,.01,
-.011064,.010571,
-.010571,.011064,
-.01,.011464,
-.009368,.011759,
-.008695,.011939,
-.008,.012,
.008,.012,
.008695,.011939,
.009368,.011759,
.01,.011464,
.010571,.011064,
.011064,.010571,
.011464,.01,
.011759,.009368,
.011939,.008695,
.012,.008,
.012,-.008,
.011939,-.008695,
.011759,-.009368,
.011464,-.01,
.011064,-.010571,
.010571,-.011064,
.01,-.011464,
.009368,-.011759,
.008695,-.011939,
.008,-.012,
0.0*
%
%ADD20MACRO20*%
%AMMACRO17*
4,1,40,.011,.007,
.011,-.007,
.010939,-.007695,
.010759,-.008368,
.010464,-.009,
.010064,-.009571,
.009571,-.010064,
.009,-.010464,
.008368,-.010759,
.007695,-.010939,
.007,-.011,
-.007,-.011,
-.007695,-.010939,
-.008368,-.010759,
-.009,-.010464,
-.009571,-.010064,
-.010064,-.009571,
-.010464,-.009,
-.010759,-.008368,
-.010939,-.007695,
-.011,-.007,
-.011,.007,
-.010939,.007695,
-.010759,.008368,
-.010464,.009,
-.010064,.009571,
-.009571,.010064,
-.009,.010464,
-.008368,.010759,
-.007695,.010939,
-.007,.011,
.007,.011,
.007695,.010939,
.008368,.010759,
.009,.010464,
.009571,.010064,
.010064,.009571,
.010464,.009,
.010759,.008368,
.010939,.007695,
.011,.007,
0.0*
%
%ADD17MACRO17*%
%AMMACRO30*
4,1,40,.013,-.017,
-.013,-.017,
-.013695,-.016939,
-.014368,-.016759,
-.015,-.016464,
-.015571,-.016064,
-.016064,-.015571,
-.016464,-.015,
-.016759,-.014368,
-.016939,-.013695,
-.017,-.013,
-.017,.013,
-.016939,.013695,
-.016759,.014368,
-.016464,.015,
-.016064,.015571,
-.015571,.016064,
-.015,.016464,
-.014368,.016759,
-.013695,.016939,
-.013,.017,
.013,.017,
.013695,.016939,
.014368,.016759,
.015,.016464,
.015571,.016064,
.016064,.015571,
.016464,.015,
.016759,.014368,
.016939,.013695,
.017,.013,
.017,-.013,
.016939,-.013695,
.016759,-.014368,
.016464,-.015,
.016064,-.015571,
.015571,-.016064,
.015,-.016464,
.014368,-.016759,
.013695,-.016939,
.013,-.017,
0.0*
%
%ADD30MACRO30*%
%AMMACRO26*
4,1,40,.012,.008,
.012,-.008,
.011939,-.008695,
.011759,-.009368,
.011464,-.01,
.011064,-.010571,
.010571,-.011064,
.01,-.011464,
.009368,-.011759,
.008695,-.011939,
.008,-.012,
-.008,-.012,
-.008695,-.011939,
-.009368,-.011759,
-.01,-.011464,
-.010571,-.011064,
-.011064,-.010571,
-.011464,-.01,
-.011759,-.009368,
-.011939,-.008695,
-.012,-.008,
-.012,.008,
-.011939,.008695,
-.011759,.009368,
-.011464,.01,
-.011064,.010571,
-.010571,.011064,
-.01,.011464,
-.009368,.011759,
-.008695,.011939,
-.008,.012,
.008,.012,
.008695,.011939,
.009368,.011759,
.01,.011464,
.010571,.011064,
.011064,.010571,
.011464,.01,
.011759,.009368,
.011939,.008695,
.012,.008,
0.0*
%
%ADD26MACRO26*%
%AMMACRO19*
4,1,40,.008,-.012,
-.008,-.012,
-.008695,-.011939,
-.009368,-.011759,
-.01,-.011464,
-.010571,-.011064,
-.011064,-.010571,
-.011464,-.01,
-.011759,-.009368,
-.011939,-.008695,
-.012,-.008,
-.012,.008,
-.011939,.008695,
-.011759,.009368,
-.011464,.01,
-.011064,.010571,
-.010571,.011064,
-.01,.011464,
-.009368,.011759,
-.008695,.011939,
-.008,.012,
.008,.012,
.008695,.011939,
.009368,.011759,
.01,.011464,
.010571,.011064,
.011064,.010571,
.011464,.01,
.011759,.009368,
.011939,.008695,
.012,.008,
.012,-.008,
.011939,-.008695,
.011759,-.009368,
.011464,-.01,
.011064,-.010571,
.010571,-.011064,
.01,-.011464,
.009368,-.011759,
.008695,-.011939,
.008,-.012,
0.0*
%
%ADD19MACRO19*%
%ADD36C,.02*%
%ADD37C,.006*%
G75*
%LPD*%
G75*
G54D10*
X-14755Y415558D03*
X-12454Y45507D03*
X29461Y718854D03*
X141466Y655356D03*
X395935Y76695D03*
X508569Y15093D03*
X554126Y315939D03*
Y685624D03*
G54D20*
X281083Y30028D03*
X328034Y179834D03*
G54D11*
X20847Y701602D03*
X32739Y30456D03*
X514356Y57612D03*
G54D30*
X307400Y46300D03*
G54D12*
X44685Y19685D03*
Y85039D03*
G54D21*
X293329Y58557D03*
G54D13*
X54724Y24803D03*
Y28740D03*
Y32677D03*
Y36614D03*
Y40551D03*
Y44488D03*
Y48425D03*
Y52362D03*
Y56299D03*
Y60236D03*
Y64173D03*
Y68110D03*
Y72047D03*
Y75984D03*
Y79921D03*
G54D22*
X287729Y58557D03*
G54D31*
X313000Y46300D03*
G54D32*
X316624Y56703D03*
X319400Y141500D03*
X325624Y56703D03*
X328400Y141500D03*
X349900Y29400D03*
X358900D03*
G54D23*
X300444Y54732D03*
X307544Y57292D03*
Y52172D03*
G54D14*
X261939Y10864D03*
X261403Y18848D03*
X292129Y215485D03*
X288498Y207172D03*
X328196Y32237D03*
X337494Y177470D03*
X331841Y233317D03*
X470551Y112318D03*
X459514Y113175D03*
X547629Y215319D03*
X549807Y89951D03*
G54D15*
X272221Y22319D03*
X268346Y29819D03*
X276096D03*
X319229Y172944D03*
X315354Y180444D03*
X323104D03*
G54D24*
X297578Y81023D03*
Y78071D03*
Y75118D03*
Y98740D03*
Y95787D03*
Y92835D03*
Y89882D03*
Y86929D03*
Y83976D03*
X322106Y81023D03*
Y78071D03*
Y75118D03*
X308208Y81023D03*
Y78071D03*
Y75118D03*
X322106Y98740D03*
Y95787D03*
Y92835D03*
Y89882D03*
Y86929D03*
Y83976D03*
X308208Y98740D03*
Y95787D03*
Y92835D03*
Y89882D03*
Y86929D03*
Y83976D03*
X332736Y81023D03*
Y78071D03*
Y75118D03*
Y98740D03*
Y95787D03*
Y92835D03*
Y89882D03*
Y86929D03*
Y83976D03*
G54D33*
X318743Y50919D03*
X485348Y106794D03*
G54D16*
X267500Y52500D03*
Y47500D03*
Y42500D03*
Y37500D03*
X287500D03*
Y42500D03*
Y47500D03*
Y52500D03*
X309000Y149500D03*
Y164500D03*
Y159500D03*
Y154500D03*
X309131Y193554D03*
Y188554D03*
Y203554D03*
Y198554D03*
X338631Y52054D03*
Y47054D03*
Y42054D03*
Y37054D03*
X329000Y149500D03*
Y154500D03*
Y159500D03*
Y164500D03*
X329131Y188554D03*
Y193554D03*
Y198554D03*
Y203554D03*
X358631Y37054D03*
Y42054D03*
Y47054D03*
Y52054D03*
G54D25*
X289800Y150000D03*
X300800D03*
X289800Y158700D03*
X300800D03*
G54D34*
X322343Y50919D03*
X488948Y106794D03*
G54D26*
X296700Y164800D03*
X519597Y106778D03*
G54D17*
X285083Y26528D03*
X332000Y176300D03*
G54D35*
X483520Y101104D03*
X491120D03*
X521558Y101034D03*
X513958D03*
G54D36*
G01X-139981Y-146685D02*
G02I-12000J0D01*
G01X-145131D02*
G02I-6850J0D01*
G01X-135981D02*
X-167981D01*
G01X-135981Y-162685D02*
Y-242685D01*
G01D02*
X971619D01*
G01X-135981Y-198185D02*
X971619D01*
G01X-151981Y-162685D02*
Y-130685D01*
G01X-135981Y-162685D02*
X971619D01*
G01X184119D02*
Y-242685D01*
G01X321619Y-162685D02*
Y-242685D01*
G01X436619Y-162685D02*
Y-242685D01*
G01X604119Y-162685D02*
Y-242685D01*
G01X774119Y-162685D02*
Y-242685D01*
G01X971619Y-162685D02*
Y-242685D01*
G01X999619Y-146685D02*
G02I-12000J0D01*
G01X1003619D02*
X971619D01*
G01X994469D02*
G02I-6850J0D01*
G01X987619Y-162685D02*
Y-130685D01*
G54D27*
X293100Y164800D03*
X515997Y106778D03*
G54D18*
X285083Y29928D03*
X332000Y179700D03*
G54D37*
G01X-116181Y-215185D02*
Y-232685D01*
G01X-121203Y-215185D02*
X-111159D01*
G01X-103048Y-232685D02*
Y-215185D01*
X-97808D01*
X-96061Y-216060D01*
X-94751Y-218102D01*
X-94314Y-220435D01*
X-94751Y-222768D01*
X-95843Y-224518D01*
X-97808Y-225394D01*
X-103048D01*
G01X-58878Y-216644D02*
X-60188Y-215768D01*
X-61716Y-215185D01*
X-63463D01*
X-65428Y-216060D01*
X-66956Y-217518D01*
X-68048Y-219269D01*
X-68921Y-222185D01*
X-69140Y-224810D01*
X-68703Y-227435D01*
X-68048Y-229185D01*
X-66738Y-230935D01*
X-65209Y-232102D01*
X-63681Y-232685D01*
X-62153D01*
X-60624Y-232102D01*
X-59314Y-231227D01*
X-58222Y-230061D01*
G01X-49893Y-232685D02*
Y-215185D01*
G01Y-223643D02*
X-48801Y-222185D01*
X-47709Y-221310D01*
X-45963Y-221019D01*
X-44653Y-221310D01*
X-43124Y-222477D01*
X-42469Y-224227D01*
Y-232685D01*
G01X-24751D02*
Y-221019D01*
G01Y-223060D02*
X-25624Y-221894D01*
X-26935Y-221310D01*
X-28463Y-221019D01*
X-29991Y-221602D01*
X-31301Y-222768D01*
X-32175Y-224518D01*
X-32611Y-226852D01*
X-32175Y-229185D01*
X-31301Y-230935D01*
X-29991Y-232102D01*
X-28463Y-232685D01*
X-26935Y-232393D01*
X-25624Y-231519D01*
X-24751Y-230352D01*
G01X-14893Y-232685D02*
Y-221019D01*
G01Y-223935D02*
X-14019Y-222477D01*
X-12709Y-221310D01*
X-10963Y-221019D01*
X-9435Y-221310D01*
X-8124Y-222477D01*
X-7469Y-224518D01*
Y-232685D01*
G01X2607D02*
Y-221019D01*
G01Y-223935D02*
X3481Y-222477D01*
X4791Y-221310D01*
X6537Y-221019D01*
X8065Y-221310D01*
X9376Y-222477D01*
X10031Y-224518D01*
Y-232685D01*
G01X20544Y-224810D02*
X27531D01*
X26876Y-222768D01*
X25784Y-221602D01*
X24256Y-221019D01*
X22727Y-221310D01*
X21417Y-222185D01*
X20544Y-224227D01*
X20107Y-225977D01*
Y-227727D01*
X20544Y-229477D01*
X21636Y-231227D01*
X22946Y-232393D01*
X24474Y-232685D01*
X26002Y-232102D01*
X27531Y-230352D01*
G01X41319Y-232685D02*
Y-215185D01*
G01X71734Y-232685D02*
Y-215185D01*
G01X80904D02*
Y-232685D01*
G01Y-223935D02*
X71734D01*
G01X89016Y-232685D02*
Y-215185D01*
X93382D01*
X95129Y-216060D01*
X96439Y-217227D01*
X97531Y-218976D01*
X98404Y-221019D01*
X98622Y-223935D01*
X98404Y-226852D01*
X97531Y-228894D01*
X96439Y-230644D01*
X95129Y-231810D01*
X93382Y-232685D01*
X89016D01*
G01X106516D02*
Y-215185D01*
X110882D01*
X112629Y-216060D01*
X113939Y-217227D01*
X115031Y-218976D01*
X115904Y-221019D01*
X116122Y-223935D01*
X115904Y-226852D01*
X115031Y-228894D01*
X113939Y-230644D01*
X112629Y-231810D01*
X110882Y-232685D01*
X106516D01*
G01X148065Y-223352D02*
X148939Y-222477D01*
X149594Y-221019D01*
X150031Y-218976D01*
X149594Y-217227D01*
X148721Y-216060D01*
X147192Y-215185D01*
X141297D01*
Y-232685D01*
X148502D01*
X150031Y-231519D01*
X150904Y-229768D01*
X151341Y-227727D01*
X150904Y-225685D01*
X149594Y-223935D01*
X148065Y-223352D01*
X141297D01*
G01X159452Y-232685D02*
Y-215185D01*
X164692D01*
X166439Y-216060D01*
X167749Y-218102D01*
X168186Y-220435D01*
X167749Y-222768D01*
X166657Y-224518D01*
X164692Y-225394D01*
X159452D01*
G01X-16858Y-187685D02*
Y-170185D01*
X-11181Y-184768D01*
X-5504Y-170185D01*
Y-187685D01*
G01X6319D02*
X5009Y-187393D01*
X3699Y-186227D01*
X2825Y-184185D01*
X2389Y-181852D01*
X2825Y-179518D01*
X3699Y-177477D01*
X5009Y-176310D01*
X6319Y-176019D01*
X7629Y-176310D01*
X8939Y-177477D01*
X9812Y-179518D01*
X10031Y-181852D01*
X9812Y-184185D01*
X8939Y-186227D01*
X7629Y-187393D01*
X6319Y-187685D01*
G01X27749Y-170185D02*
Y-187685D01*
G01Y-185061D02*
X26876Y-186519D01*
X25565Y-187393D01*
X24037Y-187685D01*
X22291Y-187102D01*
X20981Y-185644D01*
X20107Y-183894D01*
X19889Y-181852D01*
X20107Y-179810D01*
X20981Y-178060D01*
X22291Y-176602D01*
X24037Y-176019D01*
X25565Y-176310D01*
X26657Y-176894D01*
X27749Y-178060D01*
G01X38044Y-179810D02*
X45031D01*
X44376Y-177768D01*
X43284Y-176602D01*
X41756Y-176019D01*
X40227Y-176310D01*
X38917Y-177185D01*
X38044Y-179227D01*
X37607Y-180977D01*
Y-182727D01*
X38044Y-184477D01*
X39136Y-186227D01*
X40446Y-187393D01*
X41974Y-187685D01*
X43502Y-187102D01*
X45031Y-185352D01*
G01X58819Y-187685D02*
Y-170185D01*
G01X204702Y-187685D02*
Y-170185D01*
X209942D01*
X211689Y-171060D01*
X212999Y-173102D01*
X213436Y-175435D01*
X212999Y-177768D01*
X211907Y-179518D01*
X209942Y-180394D01*
X204702D01*
G01X231372Y-171644D02*
X230062Y-170768D01*
X228534Y-170185D01*
X226787D01*
X224822Y-171060D01*
X223294Y-172518D01*
X222202Y-174269D01*
X221329Y-177185D01*
X221110Y-179810D01*
X221547Y-182435D01*
X222202Y-184185D01*
X223512Y-185935D01*
X225041Y-187102D01*
X226569Y-187685D01*
X228097D01*
X229626Y-187102D01*
X230936Y-186227D01*
X232028Y-185061D01*
G01X245815Y-178352D02*
X246689Y-177477D01*
X247344Y-176019D01*
X247781Y-173976D01*
X247344Y-172227D01*
X246471Y-171060D01*
X244942Y-170185D01*
X239047D01*
Y-187685D01*
X246252D01*
X247781Y-186519D01*
X248654Y-184768D01*
X249091Y-182727D01*
X248654Y-180685D01*
X247344Y-178935D01*
X245815Y-178352D01*
X239047D01*
G01X255019Y-193518D02*
X268119D01*
G01X274047Y-187685D02*
Y-170185D01*
X284091Y-187685D01*
Y-170185D01*
G01X296569Y-187685D02*
X294822Y-187393D01*
X293294Y-186227D01*
X291984Y-184477D01*
X291110Y-182435D01*
X290674Y-180102D01*
Y-177768D01*
X291110Y-175435D01*
X291984Y-173393D01*
X293294Y-171644D01*
X294822Y-170477D01*
X296569Y-170185D01*
X298315Y-170477D01*
X299844Y-171644D01*
X301154Y-173393D01*
X302028Y-175435D01*
X302464Y-177768D01*
Y-180102D01*
X302028Y-182435D01*
X301154Y-184477D01*
X299844Y-186227D01*
X298315Y-187393D01*
X296569Y-187685D01*
G01X217819Y-232685D02*
Y-215185D01*
X215199Y-218685D01*
G01Y-232685D02*
X220439D01*
G01X234882D02*
X235319Y-228894D01*
X235974Y-225685D01*
X236847Y-222768D01*
X237939Y-219560D01*
X239686Y-215185D01*
X230952D01*
G01X248016Y-229185D02*
X249325Y-231227D01*
X251072Y-232393D01*
X253037Y-232685D01*
X254784Y-232393D01*
X256531Y-230935D01*
X257622Y-229185D01*
X257841Y-227435D01*
X257404Y-225394D01*
X255876Y-223935D01*
X254347Y-223352D01*
X252382D01*
G01X254347D02*
X255657Y-222477D01*
X256749Y-221019D01*
X257186Y-219269D01*
X256749Y-217518D01*
X255657Y-216060D01*
X253692Y-215185D01*
X251727Y-215477D01*
X249762Y-216644D01*
G01X270319Y-215185D02*
X268572Y-215768D01*
X267262Y-217227D01*
X266389Y-218976D01*
X265734Y-221310D01*
X265516Y-223935D01*
X265734Y-226560D01*
X266389Y-228894D01*
X267262Y-230644D01*
X268572Y-232102D01*
X270319Y-232685D01*
X272065Y-232102D01*
X273376Y-230644D01*
X274249Y-228894D01*
X274904Y-226560D01*
X275122Y-223935D01*
X274904Y-221310D01*
X274249Y-218976D01*
X273376Y-217227D01*
X272065Y-215768D01*
X270319Y-215185D01*
G01X287819Y-232685D02*
Y-215185D01*
X285199Y-218685D01*
G01Y-232685D02*
X290439D01*
G01X365784Y-230352D02*
X367531Y-231810D01*
X369496Y-232685D01*
X371242D01*
X372989Y-231810D01*
X374299Y-230352D01*
X374954Y-228310D01*
X374517Y-226269D01*
X373426Y-224518D01*
X371461Y-223352D01*
X368841Y-222768D01*
X367312Y-221602D01*
X366657Y-219560D01*
X367094Y-217518D01*
X368186Y-216060D01*
X369714Y-215185D01*
X371242D01*
X372771Y-215768D01*
X374081Y-217227D01*
G01X382410Y-232685D02*
X387869Y-215185D01*
X393328Y-232685D01*
G01X391362Y-226560D02*
X384375D01*
G01X347410Y-170185D02*
X352869Y-187685D01*
X358328Y-170185D01*
G01X374736Y-187685D02*
X366002D01*
Y-170185D01*
X374736D01*
G01X371242Y-178643D02*
X366002D01*
G01X383502Y-187685D02*
Y-170185D01*
X388961D01*
X390707Y-171060D01*
X391799Y-172227D01*
X392236Y-174560D01*
X391799Y-176894D01*
X390489Y-178352D01*
X388961Y-179227D01*
X383502D01*
G01X388961D02*
X392236Y-187685D01*
G01X405369Y-188268D02*
X404932Y-187977D01*
Y-187393D01*
X405369Y-187102D01*
X405806Y-187393D01*
Y-187977D01*
X405369Y-188268D01*
G01X480952Y-170185D02*
Y-187685D01*
X489686D01*
G01X506749D02*
Y-176019D01*
G01Y-178060D02*
X505876Y-176894D01*
X504565Y-176310D01*
X503037Y-176019D01*
X501509Y-176602D01*
X500199Y-177768D01*
X499325Y-179518D01*
X498889Y-181852D01*
X499325Y-184185D01*
X500199Y-185935D01*
X501509Y-187102D01*
X503037Y-187685D01*
X504565Y-187393D01*
X505876Y-186519D01*
X506749Y-185352D01*
G01X515734Y-192935D02*
X517044Y-193518D01*
X518791Y-192935D01*
X519882Y-191769D01*
X520756Y-190310D01*
X522065Y-185644D01*
X524904Y-176019D01*
G01X517917D02*
X522065Y-185644D01*
G01X534544Y-179810D02*
X541531D01*
X540876Y-177768D01*
X539784Y-176602D01*
X538256Y-176019D01*
X536727Y-176310D01*
X535417Y-177185D01*
X534544Y-179227D01*
X534107Y-180977D01*
Y-182727D01*
X534544Y-184477D01*
X535636Y-186227D01*
X536946Y-187393D01*
X538474Y-187685D01*
X540002Y-187102D01*
X541531Y-185352D01*
G01X552262Y-187685D02*
Y-176019D01*
G01Y-178352D02*
X553354Y-177185D01*
X554446Y-176310D01*
X555974Y-176019D01*
X557065Y-176310D01*
X558376Y-177185D01*
G01X544823Y-223352D02*
X543949Y-222477D01*
X543294Y-221019D01*
X542857Y-218976D01*
X543294Y-217227D01*
X544167Y-216060D01*
X545696Y-215185D01*
X551591D01*
Y-232685D01*
X544386D01*
X542857Y-231519D01*
X541984Y-229768D01*
X541547Y-227727D01*
X541984Y-225685D01*
X543294Y-223935D01*
X544823Y-223352D01*
X551591D01*
G01X533654Y-230352D02*
X531907Y-231810D01*
X529942Y-232685D01*
X528196D01*
X526449Y-231810D01*
X525139Y-230352D01*
X524484Y-228310D01*
X524921Y-226269D01*
X526012Y-224518D01*
X527977Y-223352D01*
X530597Y-222768D01*
X532126Y-221602D01*
X532781Y-219560D01*
X532344Y-217518D01*
X531252Y-216060D01*
X529724Y-215185D01*
X528196D01*
X526667Y-215768D01*
X525357Y-217227D01*
G01X517246Y-232685D02*
Y-215185D01*
X511569Y-229768D01*
X505892Y-215185D01*
Y-232685D01*
G01X498872D02*
Y-215185D01*
X494506D01*
X492759Y-216060D01*
X491449Y-217227D01*
X490357Y-218976D01*
X489484Y-221019D01*
X489266Y-223935D01*
X489484Y-226852D01*
X490357Y-228894D01*
X491449Y-230644D01*
X492759Y-231810D01*
X494506Y-232685D01*
X498872D01*
G01X623066Y-187685D02*
Y-170185D01*
X627432D01*
X629179Y-171060D01*
X630489Y-172227D01*
X631581Y-173976D01*
X632454Y-176019D01*
X632672Y-178935D01*
X632454Y-181852D01*
X631581Y-183894D01*
X630489Y-185644D01*
X629179Y-186810D01*
X627432Y-187685D01*
X623066D01*
G01X642094Y-179810D02*
X649081D01*
X648426Y-177768D01*
X647334Y-176602D01*
X645806Y-176019D01*
X644277Y-176310D01*
X642967Y-177185D01*
X642094Y-179227D01*
X641657Y-180977D01*
Y-182727D01*
X642094Y-184477D01*
X643186Y-186227D01*
X644496Y-187393D01*
X646024Y-187685D01*
X647552Y-187102D01*
X649081Y-185352D01*
G01X659594Y-185644D02*
X660686Y-186810D01*
X662214Y-187685D01*
X663524D01*
X664834Y-187102D01*
X665707Y-186227D01*
X666144Y-185061D01*
X665926Y-183310D01*
X665052Y-182435D01*
X661122Y-180685D01*
X660249Y-178643D01*
X660686Y-177185D01*
X661559Y-176310D01*
X662869Y-176019D01*
X664179Y-176310D01*
X665489Y-177185D01*
G01X680369Y-176019D02*
Y-187685D01*
G01Y-171352D02*
X679932Y-171060D01*
Y-170477D01*
X680369Y-170185D01*
X680806Y-170477D01*
Y-171060D01*
X680369Y-171352D01*
G01X694812Y-192060D02*
X696341Y-193227D01*
X698087Y-193518D01*
X699615Y-193227D01*
X700926Y-191769D01*
X701799Y-189727D01*
Y-176019D01*
G01Y-178352D02*
X700926Y-177185D01*
X699615Y-176310D01*
X698087Y-176019D01*
X696341Y-176602D01*
X695249Y-177768D01*
X694375Y-179810D01*
X693939Y-181852D01*
X694157Y-183602D01*
X695031Y-185644D01*
X696341Y-187102D01*
X698087Y-187685D01*
X699397Y-187393D01*
X700926Y-186227D01*
X701799Y-185061D01*
G01X711657Y-187685D02*
Y-176019D01*
G01Y-178935D02*
X712531Y-177477D01*
X713841Y-176310D01*
X715587Y-176019D01*
X717115Y-176310D01*
X718426Y-177477D01*
X719081Y-179518D01*
Y-187685D01*
G01X729594Y-179810D02*
X736581D01*
X735926Y-177768D01*
X734834Y-176602D01*
X733306Y-176019D01*
X731777Y-176310D01*
X730467Y-177185D01*
X729594Y-179227D01*
X729157Y-180977D01*
Y-182727D01*
X729594Y-184477D01*
X730686Y-186227D01*
X731996Y-187393D01*
X733524Y-187685D01*
X735052Y-187102D01*
X736581Y-185352D01*
G01X747312Y-187685D02*
Y-176019D01*
G01Y-178352D02*
X748404Y-177185D01*
X749496Y-176310D01*
X751024Y-176019D01*
X752115Y-176310D01*
X753426Y-177185D01*
G01X664179Y-223935D02*
X668546D01*
Y-229185D01*
X667236Y-230935D01*
X665707Y-232102D01*
X663524Y-232685D01*
X661341Y-232102D01*
X659812Y-230935D01*
X658502Y-229185D01*
X657629Y-227143D01*
X657192Y-224810D01*
Y-222768D01*
X657629Y-221019D01*
X658502Y-218976D01*
X659812Y-217227D01*
X661122Y-216060D01*
X662869Y-215185D01*
X664397D01*
X666144Y-215768D01*
X667454Y-216935D01*
G01X684736Y-232685D02*
X676002D01*
Y-215185D01*
X684736D01*
G01X681242Y-223643D02*
X676002D01*
G01X693502Y-215185D02*
Y-232685D01*
X702236D01*
G01X715369D02*
X713622Y-232393D01*
X712094Y-231227D01*
X710784Y-229477D01*
X709910Y-227435D01*
X709474Y-225102D01*
Y-222768D01*
X709910Y-220435D01*
X710784Y-218393D01*
X712094Y-216644D01*
X713622Y-215477D01*
X715369Y-215185D01*
X717115Y-215477D01*
X718644Y-216644D01*
X719954Y-218393D01*
X720828Y-220435D01*
X721264Y-222768D01*
Y-225102D01*
X720828Y-227435D01*
X719954Y-229477D01*
X718644Y-231227D01*
X717115Y-232393D01*
X715369Y-232685D01*
G01X794069Y-215185D02*
X792322Y-215768D01*
X791012Y-217227D01*
X790139Y-218976D01*
X789484Y-221310D01*
X789266Y-223935D01*
X789484Y-226560D01*
X790139Y-228894D01*
X791012Y-230644D01*
X792322Y-232102D01*
X794069Y-232685D01*
X795815Y-232102D01*
X797126Y-230644D01*
X797999Y-228894D01*
X798654Y-226560D01*
X798872Y-223935D01*
X798654Y-221310D01*
X797999Y-218976D01*
X797126Y-217227D01*
X795815Y-215768D01*
X794069Y-215185D01*
G01X807421Y-225394D02*
X808949Y-223352D01*
X810259Y-222185D01*
X812006Y-221602D01*
X813534Y-222185D01*
X814626Y-223352D01*
X815499Y-225102D01*
X815717Y-227143D01*
X815499Y-228894D01*
X814626Y-230644D01*
X813315Y-232102D01*
X811787Y-232685D01*
X810041Y-232102D01*
X808512Y-230352D01*
X807639Y-227727D01*
X807421Y-224810D01*
X807857Y-221019D01*
X808512Y-218976D01*
X809604Y-216935D01*
X811132Y-215477D01*
X812661Y-215185D01*
X814189Y-215768D01*
X815281Y-217227D01*
G01X825139Y-233268D02*
X832999Y-215185D01*
G01X842421Y-218102D02*
X843731Y-216352D01*
X845259Y-215477D01*
X847006Y-215185D01*
X849189Y-215768D01*
X850717Y-217227D01*
X851154Y-218976D01*
X850936Y-220727D01*
X850062Y-222185D01*
X845696Y-225102D01*
X843731Y-227143D01*
X842421Y-230061D01*
X841984Y-232685D01*
X851154D01*
G01X859921Y-218102D02*
X861231Y-216352D01*
X862759Y-215477D01*
X864506Y-215185D01*
X866689Y-215768D01*
X868217Y-217227D01*
X868654Y-218976D01*
X868436Y-220727D01*
X867562Y-222185D01*
X863196Y-225102D01*
X861231Y-227143D01*
X859921Y-230061D01*
X859484Y-232685D01*
X868654D01*
G01X877639Y-233268D02*
X885499Y-215185D01*
G01X894921Y-218102D02*
X896231Y-216352D01*
X897759Y-215477D01*
X899506Y-215185D01*
X901689Y-215768D01*
X903217Y-217227D01*
X903654Y-218976D01*
X903436Y-220727D01*
X902562Y-222185D01*
X898196Y-225102D01*
X896231Y-227143D01*
X894921Y-230061D01*
X894484Y-232685D01*
X903654D01*
G01X916569Y-215185D02*
X914822Y-215768D01*
X913512Y-217227D01*
X912639Y-218976D01*
X911984Y-221310D01*
X911766Y-223935D01*
X911984Y-226560D01*
X912639Y-228894D01*
X913512Y-230644D01*
X914822Y-232102D01*
X916569Y-232685D01*
X918315Y-232102D01*
X919626Y-230644D01*
X920499Y-228894D01*
X921154Y-226560D01*
X921372Y-223935D01*
X921154Y-221310D01*
X920499Y-218976D01*
X919626Y-217227D01*
X918315Y-215768D01*
X916569Y-215185D01*
G01X934069Y-232685D02*
Y-215185D01*
X931449Y-218685D01*
G01Y-232685D02*
X936689D01*
G01X951132D02*
X951569Y-228894D01*
X952224Y-225685D01*
X953097Y-222768D01*
X954189Y-219560D01*
X955936Y-215185D01*
X947202D01*
G01X841766Y-187685D02*
Y-170185D01*
X846132D01*
X847879Y-171060D01*
X849189Y-172227D01*
X850281Y-173976D01*
X851154Y-176019D01*
X851372Y-178935D01*
X851154Y-181852D01*
X850281Y-183894D01*
X849189Y-185644D01*
X847879Y-186810D01*
X846132Y-187685D01*
X841766D01*
G01X867999D02*
Y-176019D01*
G01Y-178060D02*
X867126Y-176894D01*
X865815Y-176310D01*
X864287Y-176019D01*
X862759Y-176602D01*
X861449Y-177768D01*
X860575Y-179518D01*
X860139Y-181852D01*
X860575Y-184185D01*
X861449Y-185935D01*
X862759Y-187102D01*
X864287Y-187685D01*
X865815Y-187393D01*
X867126Y-186519D01*
X867999Y-185352D01*
G01X881569Y-170185D02*
Y-187685D01*
G01X878512Y-176019D02*
X884626D01*
G01X895794Y-179810D02*
X902781D01*
X902126Y-177768D01*
X901034Y-176602D01*
X899506Y-176019D01*
X897977Y-176310D01*
X896667Y-177185D01*
X895794Y-179227D01*
X895357Y-180977D01*
Y-182727D01*
X895794Y-184477D01*
X896886Y-186227D01*
X898196Y-187393D01*
X899724Y-187685D01*
X901252Y-187102D01*
X902781Y-185352D01*
G01X-25590Y9843D02*
G03X-15748Y0I9842J-1D01*
G01X-25590Y89370D02*
Y9843D01*
G01X-23622Y91339D02*
G03X-25590Y89370I1J-1969D01*
G01X-7874Y91339D02*
X-23622D01*
G01X-25590Y109055D02*
G03X-21653Y105118I3937J0D01*
G01X-25590Y357874D02*
Y109055D01*
G01X-21653Y105118D02*
X261811D01*
G01X-25590Y371654D02*
G03X-23622Y369685I1968J-1D01*
G01X-21653Y361811D02*
G03X-25590Y357874I0J-3937D01*
G01X1969Y361811D02*
X-21653D01*
G01X-7874Y369685D02*
X-23622D01*
G01X-25590Y459055D02*
Y371654D01*
G01X-23622Y461024D02*
G03X-25590Y459055I1J-1969D01*
G01X-7874Y461024D02*
X-23622D01*
G01X-25590Y478740D02*
G03X-21653Y474803I3937J0D01*
G01X-25590Y727559D02*
Y478740D01*
G01X-21653Y474803D02*
X261811D01*
G01X-21653Y731496D02*
G03X-25590Y727559I0J-3937D01*
G01X1969Y731496D02*
X-21653D01*
G01X-11811Y0D02*
G03X-7874Y3937I0J3937D01*
G01X-11811Y0D02*
X-15748D01*
G01X0Y3937D02*
G03X3937Y0I3937J0D01*
G01X-7874Y33071D02*
Y3937D01*
G01X0Y87402D02*
Y3937D01*
G01Y33071D02*
G03X-7874I-3937J0D01*
G01Y58268D02*
G03X0I3937J0D01*
G01X-7874Y91339D02*
Y58268D01*
G01X3937Y91339D02*
G03X0Y87402I0J-3937D01*
G01X5906Y357874D02*
G03X1969Y361811I-3937J0D01*
G01X0Y373622D02*
G03X3937Y369685I3937J0D01*
G01X-7874Y402756D02*
Y369685D01*
G01X0Y457087D02*
Y373622D01*
G01Y402756D02*
G03X-7874I-3937J0D01*
G01Y427953D02*
G03X0I3937J0D01*
G01X-7874Y461024D02*
Y427953D01*
G01X3937Y461024D02*
G03X0Y457087I0J-3937D01*
G01X5906Y727559D02*
G03X1969Y731496I-3937J0D01*
G01X3937Y0D02*
X372048D01*
G01X192914Y91339D02*
X3937D01*
G01X5906Y290748D02*
G03X9843Y286811I3937J0D01*
G01X5906Y357874D02*
Y290748D01*
G01X69488Y286811D02*
X9843D01*
G01X13780Y315650D02*
Y294685D01*
G01X69488D02*
X13780D01*
G01Y315650D02*
G03X5906I-3937J0D01*
G01Y340847D02*
G03X13780I3937J0D01*
G01Y361811D02*
Y340847D01*
G01X3937Y369685D02*
X372048D01*
G01X43307Y361811D02*
X13780D01*
G01X192914Y461024D02*
X3937D01*
G01X5906Y660433D02*
G03X9843Y656496I3937J0D01*
G01X5906Y727559D02*
Y660433D01*
G01X69488Y656496D02*
X9843D01*
G01X13780Y685335D02*
Y664370D01*
G01X69488D02*
X13780D01*
G01Y685335D02*
G03X5906I-3937J0D01*
G01Y710532D02*
G03X13780I3937J0D01*
G01Y729528D02*
Y710532D01*
G01X15748Y731496D02*
G03X13780Y729528I0J-1968D01*
G01X44819Y731496D02*
X15748D01*
G01X43307Y361811D02*
G03Y369685I0J3937D01*
G01X46675Y730184D02*
G03X44819Y731496I-1856J-657D01*
G01X46675Y730184D02*
G03X54098I3712J1313D01*
G01X53150Y181697D02*
G03X55118Y179729I1968J0D01*
G01X53150Y195477D02*
Y181697D01*
G01X55118Y179729D02*
X161418D01*
G01X55118Y197445D02*
G03X53150Y195477I0J-1968D01*
G01X161418Y197445D02*
X55118D01*
G01X73426Y282874D02*
G03X69488Y286811I-3937J0D01*
G01X81300Y282874D02*
G03X69488Y294685I-11811J0D01*
G01X74016Y369685D02*
G03Y361811I0J-3937D01*
G01X53150Y551382D02*
G03X55118Y549414I1968J0D01*
G01X53150Y565162D02*
Y551382D01*
G01X55118Y549414D02*
X161418D01*
G01X55118Y567130D02*
G03X53150Y565162I0J-1968D01*
G01X161418Y567130D02*
X55118D01*
G01X73426Y652559D02*
G03X69488Y656496I-3937J0D01*
G01X81300Y652559D02*
G03X69488Y664370I-11811J0D01*
G01X55954Y731496D02*
G03X54098Y730184I0J-1969D01*
G01X153544Y731496D02*
X55954D01*
G01X80709Y43307D02*
G03X82677Y41339I1968J0D01*
G01Y47244D02*
G03X80709Y45276I0J-1968D01*
G01X188977Y47244D02*
X82677D01*
G01Y41339D02*
X188977D01*
G01X80709Y45276D02*
Y43307D01*
G01X86614Y101181D02*
G03X82677Y105118I-3937J0D01*
G01X86614Y95276D02*
Y101181D01*
G01X82677Y91339D02*
G03X86614Y95276I0J3937D01*
G01X73426Y267323D02*
G03X77363Y263386I3937J0D01*
G01X73426Y267323D02*
Y282874D01*
G01X77363Y263386D02*
X159449D01*
G01X81300Y271260D02*
Y282874D01*
G01Y271260D02*
X155512D01*
G01Y361811D02*
X74016D01*
G01X80709Y412992D02*
G03X82677Y411024I1968J0D01*
G01Y416929D02*
G03X80709Y414961I0J-1968D01*
G01X188977Y416929D02*
X82677D01*
G01Y411024D02*
X188977D01*
G01X80709Y414961D02*
Y412992D01*
G01X86614Y464961D02*
Y470866D01*
G01X82677Y461024D02*
G03X86614Y464961I0J3937D01*
G01Y470866D02*
G03X82677Y474803I-3937J0D01*
G01X73426Y637008D02*
G03X77363Y633071I3937J0D01*
G01X73426Y637008D02*
Y652559D01*
G01X77363Y633071D02*
X159449D01*
G01X81300Y640945D02*
Y652559D01*
G01Y640945D02*
X155512D01*
G01X109449Y95276D02*
Y101181D01*
G01X113386Y105118D02*
G03X109449Y101181I0J-3937D01*
G01Y95276D02*
G03X113386Y91339I3937J0D01*
G01X109449Y464961D02*
Y470866D01*
G01Y464961D02*
G03X113386Y461024I3937J0D01*
G01Y474803D02*
G03X109449Y470866I0J-3937D01*
G01X161418Y179729D02*
G03X163386Y181697I0J1968D01*
G01Y195477D02*
G03X161418Y197445I-1968J0D01*
G01X159449Y263386D02*
G03X163386Y267323I0J3937D01*
G01X155512Y303937D02*
Y271260D01*
G01X163386Y303937D02*
G03X155512I-3937J0D01*
G01Y329134D02*
G03X163386I3937J0D01*
G01X155512Y361811D02*
Y329134D01*
G01X161418Y549414D02*
G03X163386Y551382I0J1968D01*
G01Y565162D02*
G03X161418Y567130I-1968J0D01*
G01X159449Y633071D02*
G03X163386Y637008I0J3937D01*
G01X155512Y673622D02*
Y640945D01*
G01X163386Y673622D02*
G03X155512I-3937J0D01*
G01Y698819D02*
G03X163386I3937J0D01*
G01X155512Y729528D02*
Y698819D01*
G01Y729528D02*
G03X153544Y731496I-1968J0D01*
G01X163386Y181697D02*
Y195477D01*
G01Y357874D02*
Y267323D01*
G01X167323Y361811D02*
G03X163386Y357874I0J-3937D01*
G01X535433Y361811D02*
X167323D01*
G01X163386Y551382D02*
Y565162D01*
G01Y727559D02*
Y637008D01*
G01X167323Y731496D02*
G03X163386Y727559I0J-3937D01*
G01X535433Y731496D02*
X167323D01*
G01X188977Y41339D02*
G03X190945Y43307I0J1968D01*
G01Y45276D02*
G03X188977Y47244I-1968J0D01*
G01X190945Y43307D02*
Y45276D01*
G01X196851Y97244D02*
G03X194882Y95276I0J-1969D01*
G01X192914Y91339D02*
G03X194882Y93307I0J1968D01*
G01X196851Y97244D02*
X269685D01*
G01X194882Y93307D02*
Y95276D01*
G01X188977Y411024D02*
G03X190945Y412992I0J1968D01*
G01Y414961D02*
G03X188977Y416929I-1968J0D01*
G01X190945Y412992D02*
Y414961D01*
G01X196851Y466929D02*
G03X194882Y464961I-1J-1968D01*
G01X192914Y461024D02*
G03X194882Y462992I0J1968D01*
G01D02*
Y464961D01*
G01X196851Y466929D02*
X269685D01*
G01Y97244D02*
G03X273622Y101181I0J3937D01*
G01Y252756D02*
Y101181D01*
G01X261811Y105118D02*
G03X265748Y109055I0J3937D01*
G01D02*
Y260630D01*
G01X273622Y165551D02*
G03X265748I-3937J0D01*
G01Y196260D02*
G03X273622I3937J0D01*
G01X269685Y264567D02*
G03X265748Y260630I0J-3937D01*
G01X277559Y256693D02*
G03X273622Y252756I0J-3937D01*
G01X342520Y264567D02*
X269685D01*
G01X254331Y361811D02*
G03Y369685I0J3937D01*
G01X261811Y474803D02*
G03X265748Y478740I0J3937D01*
G01D02*
Y630315D01*
G01X269685Y466929D02*
G03X273622Y470866I0J3937D01*
G01Y622441D02*
Y470866D01*
G01Y535236D02*
G03X265748I-3937J0D01*
G01Y565945D02*
G03X273622I3937J0D01*
G01X277559Y626378D02*
G03X273622Y622441I0J-3937D01*
G01X269685Y634252D02*
G03X265748Y630315I0J-3937D01*
G01X342520Y634252D02*
X269685D01*
G01X561024Y256693D02*
X277559D01*
G01X285040Y369685D02*
G03Y361811I0J-3937D01*
G01X561024Y626378D02*
X277559D01*
G01X342520Y264567D02*
G03X344488Y266536I0J1968D01*
G01X342520Y634252D02*
G03X344488Y636221I0J1968D01*
G01X346457Y270473D02*
G03X344488Y268504I0J-1969D01*
G01X346457Y270473D02*
X535433D01*
G01X344488Y268504D02*
Y266536D01*
G01X350394Y320473D02*
G03X348426Y318504I0J-1968D01*
G01Y316536D02*
G03X350394Y314567I1968J-1D01*
G01D02*
X456693D01*
G01Y320473D02*
X350394D01*
G01X348426Y318504D02*
Y316536D01*
G01X346457Y640158D02*
G03X344488Y638189I0J-1969D01*
G01X346457Y640158D02*
X535433D01*
G01X344488Y638189D02*
Y636221D01*
G01X350394Y690158D02*
G03X348426Y688189I0J-1968D01*
G01Y686221D02*
G03X350394Y684252I1968J-1D01*
G01D02*
X456693D01*
G01Y690158D02*
X350394D01*
G01X348426Y688189D02*
Y686221D01*
G01X383859Y1969D02*
G03X385827Y0I1968J-1D01*
G01D02*
X523622D01*
G01X372048D02*
G03X375985Y3937I0J3937D01*
G01X383859Y1969D02*
Y32677D01*
G01X375985Y3937D02*
Y94488D01*
G01X383859Y32677D02*
G03X375985I-3937J0D01*
G01Y57874D02*
G03X383859I3937J0D01*
G01D02*
Y90551D01*
G01X379922Y98425D02*
G03X375985Y94488I0J-3937D01*
G01X458071Y90551D02*
X383859D01*
G01X462008Y98425D02*
X379922D01*
G01X375985Y166334D02*
G03X377953Y164365I1969J0D01*
G01X375985Y180113D02*
Y166334D01*
G01X377953Y164365D02*
X484252D01*
G01X377953Y182082D02*
G03X375985Y180113I0J-1968D01*
G01X484252Y182082D02*
X377953D01*
G01X383859Y369685D02*
X465355D01*
G01X372048D02*
G03X375985Y373622I0J3937D01*
G01X383859Y369685D02*
Y402362D01*
G01X375985Y373622D02*
Y464173D01*
G01X383859Y402362D02*
G03X375985I-3937J0D01*
G01Y427559D02*
G03X383859I3937J0D01*
G01D02*
Y460236D01*
G01X379922Y468110D02*
G03X375985Y464173I0J-3937D01*
G01X458071Y460236D02*
X383859D01*
G01X462008Y468110D02*
X379922D01*
G01X375985Y536019D02*
G03X377953Y534050I1969J0D01*
G01D02*
X484252D01*
G01X377953Y551767D02*
G03X375985Y549799I0J-1968D01*
G01D02*
Y536019D01*
G01X484252Y551767D02*
X377953D01*
G01X429922Y260630D02*
Y266536D01*
G01X425985Y256693D02*
G03X429922Y260630I0J3937D01*
G01Y266536D02*
G03X425985Y270473I-3937J0D01*
G01X429922Y630315D02*
Y636221D01*
G01X425985Y626378D02*
G03X429922Y630315I0J3937D01*
G01Y636221D02*
G03X425985Y640158I-3937J0D01*
G01X452756Y260630D02*
G03X456693Y256693I3937J0D01*
G01X452756Y260630D02*
Y266536D01*
G01X456693Y270473D02*
G03X452756Y266536I0J-3937D01*
G01X458662Y318504D02*
G03X456693Y320473I-1969J0D01*
G01Y314567D02*
G03X458662Y316536I0J1969D01*
G01X452756Y630315D02*
G03X456693Y626378I3937J0D01*
G01X452756Y630315D02*
Y636221D01*
G01X456693Y640158D02*
G03X452756Y636221I0J-3937D01*
G01X458662Y688189D02*
G03X456693Y690158I-1969J0D01*
G01Y684252D02*
G03X458662Y686221I0J1969D01*
G01X458071Y78937D02*
G03X469882Y67126I11811J0D01*
G01X465945Y78937D02*
G03X469882Y75000I3937J0D01*
G01X458071Y90551D02*
Y78937D01*
G01X465945Y94488D02*
Y78937D01*
G01X469882Y67126D02*
X525591D01*
G01X469882Y75000D02*
X529528D01*
G01X465945Y94488D02*
G03X462008Y98425I-3937J0D01*
G01X458662Y316536D02*
Y318504D01*
G01X465355Y361811D02*
G03Y369685I0J3937D01*
G01X458071Y448622D02*
G03X469882Y436811I11811J0D01*
G01D02*
X525591D01*
G01X465945Y448622D02*
G03X469882Y444685I3937J0D01*
G01X465945Y464173D02*
G03X462008Y468110I-3937J0D01*
G01X458071Y460236D02*
Y448622D01*
G01X465945Y464173D02*
Y448622D01*
G01X469882Y444685D02*
X529528D01*
G01X458662Y686221D02*
Y688189D01*
G01X484252Y164365D02*
G03X486221Y166334I0J1969D01*
G01D02*
Y180113D01*
G01D02*
G03X484252Y182082I-1969J0D01*
G01X496063Y369685D02*
G03Y361811I0J-3937D01*
G01Y369685D02*
X525591D01*
G01X484252Y534050D02*
G03X486221Y536019I0J1969D01*
G01Y549799D02*
G03X484252Y551767I-1969J-1D01*
G01X486221Y536019D02*
Y549799D01*
G01X523622Y0D02*
G03X525591Y1969I0J1969D01*
G01X533465Y3937D02*
G03X537402Y0I3937J0D01*
G01X525591Y1969D02*
Y20965D01*
G01X533465Y3937D02*
Y71063D01*
G01X537402Y0D02*
X561024D01*
G01X533465Y20965D02*
G03X525591I-3937J0D01*
G01Y46162D02*
G03X533465I3937J0D01*
G01X525591D02*
Y67126D01*
G01X533465Y71063D02*
G03X529528Y75000I-3937J0D01*
G01X535433Y270473D02*
G03X539370Y274410I0J3937D01*
G01D02*
Y357874D01*
G01X547244Y270473D02*
X562992D01*
G01X547244D02*
Y303543D01*
G01D02*
G03X539370I-3937J0D01*
G01Y328740D02*
G03X547244I3937J0D01*
G01D02*
Y361811D01*
G01X539370Y357874D02*
G03X535433Y361811I-3937J0D01*
G01X547244D02*
X562992D01*
G01X533465Y373622D02*
G03X537402Y369685I3937J0D01*
G01X525591D02*
Y390650D01*
G01X533465Y373622D02*
Y440748D01*
G01X537402Y369685D02*
X561024D01*
G01X533465Y390650D02*
G03X525591I-3937J0D01*
G01Y415847D02*
G03X533465I3937J0D01*
G01X525591D02*
Y436811D01*
G01X533465Y440748D02*
G03X529528Y444685I-3937J0D01*
G01X535433Y640158D02*
G03X539370Y644095I0J3937D01*
G01D02*
Y727559D01*
G01X547244Y640158D02*
X562992D01*
G01X547244D02*
Y673228D01*
G01D02*
G03X539370I-3937J0D01*
G01Y698425D02*
G03X547244I3937J0D01*
G01D02*
Y727559D01*
G01X551181Y731496D02*
G03X547244Y727559I0J-3937D01*
G01X539370D02*
G03X535433Y731496I-3937J0D01*
G01X561024Y0D02*
G03X564961Y3937I0J3937D01*
G01D02*
Y252756D01*
G01D02*
G03X561024Y256693I-3937J0D01*
G01X562992Y270473D02*
G03X564961Y272441I1J1968D01*
G01D02*
Y359843D01*
G01D02*
G03X562992Y361811I-1968J0D01*
G01X561024Y369685D02*
G03X564961Y373622I0J3937D01*
G01D02*
Y622441D01*
G01D02*
G03X561024Y626378I-3937J0D01*
G01X562992Y640158D02*
G03X564961Y642126I1J1968D01*
G01D02*
Y721654D01*
G01D02*
G03X555118Y731496I-9842J0D01*
G01X551181D02*
X555118D01*
G54D19*
X281083Y26428D03*
X328034Y176234D03*
G54D28*
X306460Y32950D03*
X301340D03*
Y39450D03*
X303900D03*
X306460D03*
X317440Y213250D03*
Y219750D03*
X320000D03*
X322560Y213250D03*
Y219750D03*
G54D29*
X318960Y33000D03*
X316400D03*
X313840D03*
Y40400D03*
X316400D03*
X318960D03*
X306940Y140700D03*
X309500D03*
X312060D03*
Y133300D03*
X309500D03*
X306940D03*
X337440Y27700D03*
X340000D03*
X342560D03*
Y20300D03*
X340000D03*
X337440D03*
M02*
